# S9S_MB_2U (Grand Teton) — schematic netlist excerpt (pin names and nets, part order shuffled) for the footprints in the layout excerpt that follows; sources: Cadence DE-HDL packaged netlist, KiCad conversion of 03242023_DA0F0TMBIJ0_F0T_Motherboard_J_brd_V01_OCP.brd

R4519  Q_RES  10K 1% CHIP  pkg 0402LF  page 211 : A = P3V3 ; B = CLK_GPU_1_OE_N
C1837  Q_CAP  0.1UF 25V 10% X7R  pkg 0402  page 159 : A = P3V3_OCP_V3_2 ; B = GND

(kicad_pcb
	(version 20260206)
	(generator "pcbnew")
	(generator_version "10.0")
	(general
		(thickness 1.6)
		(legacy_teardrops no)
	)
	(paper "A4")
	(title_block
		(title "03242023_DA0F0TMBIJ0_F0T_Motherboard_J_brd_V01_OCP.brd")
		(comment 1 "Grand Teton / footprints 4749-4750 of 6105")
	)
	(layers
		(0 "F.Cu" signal "TOP")
		(4 "In1.Cu" signal "GND")
		(6 "In2.Cu" signal "IN1")
		(8 "In3.Cu" signal "GND1")
		(10 "In4.Cu" signal "IN2")
		(12 "In5.Cu" signal "GND2")
		(14 "In6.Cu" signal "IN3")
		(16 "In7.Cu" signal "GND3")
		(18 "In8.Cu" signal "VCC")
		(20 "In9.Cu" signal "VCC1")
		(22 "In10.Cu" signal "GND4")
		(24 "In11.Cu" signal "IN4")
		(26 "In12.Cu" signal "GND5")
		(28 "In13.Cu" signal "IN5")
		(30 "In14.Cu" signal "GND6")
		(32 "In15.Cu" signal "IN6")
		(34 "In16.Cu" signal "GND7")
		(2 "B.Cu" signal "BOTTOM")
		(9 "F.Adhes" user "F.Adhesive")
		(11 "B.Adhes" user "B.Adhesive")
		(13 "F.Paste" user "Package Geometry/Pastemask Top")
		(15 "B.Paste" user "Package Geometry/Pastemask Bottom")
		(5 "F.SilkS" user "Ref Des/Silkscreen Top")
		(7 "B.SilkS" user "Ref Des/Silkscreen Bottom")
		(1 "F.Mask" user "Board Geometry/Soldermask Top")
		(3 "B.Mask" user "Board Geometry/Soldermask Bottom")
		(17 "Dwgs.User" user "User.Drawings")
		(19 "Cmts.User" user "User.Comments")
		(21 "Eco1.User" user "User.Eco1")
		(23 "Eco2.User" user "User.Eco2")
		(25 "Edge.Cuts" user "Board Geometry/Outline")
		(27 "Margin" user)
		(31 "F.CrtYd" user "Package Geometry/Place Bound Top")
		(29 "B.CrtYd" user "Package Geometry/Place Bound Bottom")
		(35 "F.Fab" user "Ref Des/Assembly Top")
		(33 "B.Fab" user "Ref Des/Assembly Bottom")
	)
	(footprint ""
		(layer "B.Cu")
		(at 193.38163 -127.422148 180)
		(property "Reference" "R4519"
			(at 0 0 0)
			(layer "B.SilkS")
			(hide yes)
			(effects
				(font
					(size 1.27 1.27)
				)
				(justify mirror)
			)
		)
		(property "Value" ""
			(at 0 0 0)
			(layer "B.Fab")
			(effects
				(font
					(size 1.27 1.27)
				)
				(justify mirror)
			)
		)
		(duplicate_pad_numbers_are_jumpers no)
		(fp_line
			(start 0.7874 0.4064)
			(end 0.7874 -0.4064)
			(stroke
				(width 0.1524)
				(type default)
			)
			(layer "B.SilkS")
		)
		(fp_line
			(start 0.7874 -0.4064)
			(end -0.7874 -0.4064)
			(stroke
				(width 0.1524)
				(type default)
			)
			(layer "B.SilkS")
		)
		(fp_line
			(start -0.7874 0.4064)
			(end 0.7874 0.4064)
			(stroke
				(width 0.1524)
				(type default)
			)
			(layer "B.SilkS")
		)
		(fp_line
			(start -0.7874 -0.4064)
			(end -0.7874 0.4064)
			(stroke
				(width 0.1524)
				(type default)
			)
			(layer "B.SilkS")
		)
		(fp_line
			(start 0.67945 0.3048)
			(end 0.67945 -0.305054)
			(stroke
				(width 0.1)
				(type default)
			)
			(layer "B.Fab")
		)
		(fp_line
			(start 0.67945 -0.305054)
			(end 0.12065 -0.305054)
			(stroke
				(width 0.1)
				(type default)
			)
			(layer "B.Fab")
		)
		(fp_line
			(start 0.12065 0.3048)
			(end 0.67945 0.3048)
			(stroke
				(width 0.1)
				(type default)
			)
			(layer "B.Fab")
		)
		(fp_line
			(start 0.12065 0.2794)
			(end 0.12065 0.3048)
			(stroke
				(width 0.1)
				(type default)
			)
			(layer "B.Fab")
		)
		(fp_line
			(start 0.12065 -0.2794)
			(end -0.12065 -0.2794)
			(stroke
				(width 0.1)
				(type default)
			)
			(layer "B.Fab")
		)
		(fp_line
			(start 0.12065 -0.305054)
			(end 0.12065 -0.2794)
			(stroke
				(width 0.1)
				(type default)
			)
			(layer "B.Fab")
		)
		(fp_line
			(start -0.120396 0.3048)
			(end -0.120396 0.2794)
			(stroke
				(width 0.1)
				(type default)
			)
			(layer "B.Fab")
		)
		(fp_line
			(start -0.120396 0.2794)
			(end 0.12065 0.2794)
			(stroke
				(width 0.1)
				(type default)
			)
			(layer "B.Fab")
		)
		(fp_line
			(start -0.12065 -0.2794)
			(end -0.12065 -0.3048)
			(stroke
				(width 0.1)
				(type default)
			)
			(layer "B.Fab")
		)
		(fp_line
			(start -0.12065 -0.3048)
			(end -0.67945 -0.3048)
			(stroke
				(width 0.1)
				(type default)
			)
			(layer "B.Fab")
		)
		(fp_line
			(start -0.67945 0.3048)
			(end -0.120396 0.3048)
			(stroke
				(width 0.1)
				(type default)
			)
			(layer "B.Fab")
		)
		(fp_line
			(start -0.67945 -0.3048)
			(end -0.67945 0.3048)
			(stroke
				(width 0.1)
				(type default)
			)
			(layer "B.Fab")
		)
		(pad "1" smd circle
			(at 0.40005 0)
			(size 0 0)
			(layers "B.Cu" "B.Mask" "B.Paste")
			(net "P3V3")
		)
		(pad "2" smd circle
			(at -0.40005 0)
			(size 0 0)
			(layers "B.Cu" "B.Mask" "B.Paste")
			(net "CLK_GPU_1_OE_N")
		)
	)
	(footprint ""
		(layer "B.Cu")
		(at 62.53988 -8.981948 90)
		(property "Reference" "C1837"
			(at 0 0 90)
			(layer "B.SilkS")
			(hide yes)
			(effects
				(font
					(size 1.27 1.27)
				)
				(justify mirror)
			)
		)
		(property "Value" ""
			(at 0 0 90)
			(layer "B.Fab")
			(effects
				(font
					(size 1.27 1.27)
				)
				(justify mirror)
			)
		)
		(duplicate_pad_numbers_are_jumpers no)
		(fp_line
			(start 0.7874 -0.4064)
			(end -0.7874 -0.4064)
			(stroke
				(width 0.1524)
				(type default)
			)
			(layer "B.SilkS")
		)
		(fp_line
			(start -0.7874 -0.4064)
			(end -0.7874 0.4064)
			(stroke
				(width 0.1524)
				(type default)
			)
			(layer "B.SilkS")
		)
		(fp_line
			(start 0.7874 0.4064)
			(end 0.7874 -0.4064)
			(stroke
				(width 0.1524)
				(type default)
			)
			(layer "B.SilkS")
		)
		(fp_line
			(start -0.7874 0.4064)
			(end 0.7874 0.4064)
			(stroke
				(width 0.1524)
				(type default)
			)
			(layer "B.SilkS")
		)
		(fp_line
			(start 0.67945 -0.305054)
			(end 0.12065 -0.305054)
			(stroke
				(width 0.1)
				(type default)
			)
			(layer "B.Fab")
		)
		(fp_line
			(start 0.12065 -0.305054)
			(end 0.12065 -0.2794)
			(stroke
				(width 0.1)
				(type default)
			)
			(layer "B.Fab")
		)
		(fp_line
			(start -0.12065 -0.3048)
			(end -0.67945 -0.3048)
			(stroke
				(width 0.1)
				(type default)
			)
			(layer "B.Fab")
		)
		(fp_line
			(start -0.67945 -0.3048)
			(end -0.67945 0.3048)
			(stroke
				(width 0.1)
				(type default)
			)
			(layer "B.Fab")
		)
		(fp_line
			(start 0.12065 -0.2794)
			(end -0.12065 -0.2794)
			(stroke
				(width 0.1)
				(type default)
			)
			(layer "B.Fab")
		)
		(fp_line
			(start -0.12065 -0.2794)
			(end -0.12065 -0.3048)
			(stroke
				(width 0.1)
				(type default)
			)
			(layer "B.Fab")
		)
		(fp_line
			(start 0.12065 0.2794)
			(end 0.12065 0.3048)
			(stroke
				(width 0.1)
				(type default)
			)
			(layer "B.Fab")
		)
		(fp_line
			(start -0.120396 0.2794)
			(end 0.12065 0.2794)
			(stroke
				(width 0.1)
				(type default)
			)
			(layer "B.Fab")
		)
		(fp_line
			(start 0.67945 0.3048)
			(end 0.67945 -0.305054)
			(stroke
				(width 0.1)
				(type default)
			)
			(layer "B.Fab")
		)
		(fp_line
			(start 0.12065 0.3048)
			(end 0.67945 0.3048)
			(stroke
				(width 0.1)
				(type default)
			)
			(layer "B.Fab")
		)
		(fp_line
			(start -0.120396 0.3048)
			(end -0.120396 0.2794)
			(stroke
				(width 0.1)
				(type default)
			)
			(layer "B.Fab")
		)
		(fp_line
			(start -0.67945 0.3048)
			(end -0.120396 0.3048)
			(stroke
				(width 0.1)
				(type default)
			)
			(layer "B.Fab")
		)
		(pad "1" smd circle
			(at 0.40005 0 270)
			(size 0 0)
			(layers "B.Cu" "B.Mask" "B.Paste")
			(net "P3V3_OCP_V3_2")
		)
		(pad "2" smd circle
			(at -0.40005 0 270)
			(size 0 0)
			(layers "B.Cu" "B.Mask" "B.Paste")
			(net "GND")
		)
	)
)
